G04*
G04 #@! TF.GenerationSoftware,Altium Limited,Altium Designer,22.4.2 (48)*
G04*
G04 Layer_Color=32896*
%FSLAX25Y25*%
%MOIN*%
G70*
G04*
G04 #@! TF.SameCoordinates,446674BB-F454-490D-8607-5140536C8ADF*
G04*
G04*
G04 #@! TF.FilePolarity,Positive*
G04*
G01*
G75*
M02*
